(kicad_pcb
	(version 20260206)
	(generator "pcbnew")
	(generator_version "10.0")
	(general
		(thickness 1.6)
		(legacy_teardrops no)
	)
	(paper "A4")
	(title_block
		(title "01162023_DA0F0TEBIF0_F0T_Expander_BD_F_brd_V02_OCP.brd")
		(comment 1 "Grand Teton / footprints 5520-5525 of 9728")
	)
	(layers
		(0 "F.Cu" signal "TOP")
		(4 "In1.Cu" signal "GND")
		(6 "In2.Cu" signal "VCC")
		(8 "In3.Cu" signal "VCC1")
		(10 "In4.Cu" signal "GND1")
		(12 "In5.Cu" signal "IN1")
		(14 "In6.Cu" signal "GND2")
		(16 "In7.Cu" signal "IN2")
		(18 "In8.Cu" signal "GND3")
		(20 "In9.Cu" signal "IN3")
		(22 "In10.Cu" signal "GND4")
		(24 "In11.Cu" signal "IN4")
		(26 "In12.Cu" signal "GND5")
		(28 "In13.Cu" signal "IN5")
		(30 "In14.Cu" signal "GND6")
		(32 "In15.Cu" signal "IN6")
		(34 "In16.Cu" signal "GND7")
		(2 "B.Cu" signal "BOTTOM")
		(9 "F.Adhes" user "F.Adhesive")
		(11 "B.Adhes" user "B.Adhesive")
		(13 "F.Paste" user "Package Geometry/Pastemask Top")
		(15 "B.Paste" user "Package Geometry/Pastemask Bottom")
		(5 "F.SilkS" user "Ref Des/Silkscreen Top")
		(7 "B.SilkS" user "Ref Des/Silkscreen Bottom")
		(1 "F.Mask" user "Board Geometry/Soldermask Top")
		(3 "B.Mask" user "Board Geometry/Soldermask Bottom")
		(17 "Dwgs.User" user "User.Drawings")
		(19 "Cmts.User" user "User.Comments")
		(21 "Eco1.User" user "User.Eco1")
		(23 "Eco2.User" user "User.Eco2")
		(25 "Edge.Cuts" user "Board Geometry/Outline")
		(27 "Margin" user)
		(31 "F.CrtYd" user "Package Geometry/Place Bound Top")
		(29 "B.CrtYd" user "Package Geometry/Place Bound Bottom")
		(35 "F.Fab" user "Ref Des/Assembly Top")
		(33 "B.Fab" user "Ref Des/Assembly Bottom")
	)
	(footprint ""
		(layer "F.Cu")
		(at 347.539564 -265.949938 180)
		(property "Reference" "PR7136"
			(at 0 0 180)
			(layer "F.SilkS")
			(hide yes)
			(effects
				(font
					(size 1.27 1.27)
				)
			)
		)
		(property "Value" ""
			(at 0 0 180)
			(layer "F.Fab")
			(effects
				(font
					(size 1.27 1.27)
				)
			)
		)
		(duplicate_pad_numbers_are_jumpers no)
		(fp_line
			(start 0.7874 0.4064)
			(end -0.7874 0.4064)
			(stroke
				(width 0.1524)
				(type default)
			)
			(layer "F.SilkS")
		)
		(fp_line
			(start 0.7874 -0.4064)
			(end 0.7874 0.4064)
			(stroke
				(width 0.1524)
				(type default)
			)
			(layer "F.SilkS")
		)
		(fp_line
			(start -0.7874 0.4064)
			(end -0.7874 -0.4064)
			(stroke
				(width 0.1524)
				(type default)
			)
			(layer "F.SilkS")
		)
		(fp_line
			(start -0.7874 -0.4064)
			(end 0.7874 -0.4064)
			(stroke
				(width 0.1524)
				(type default)
			)
			(layer "F.SilkS")
		)
		(fp_line
			(start 0.67945 0.3048)
			(end 0.120396 0.3048)
			(stroke
				(width 0.1)
				(type default)
			)
			(layer "F.Fab")
		)
		(fp_line
			(start 0.67945 -0.3048)
			(end 0.67945 0.3048)
			(stroke
				(width 0.1)
				(type default)
			)
			(layer "F.Fab")
		)
		(fp_line
			(start 0.12065 -0.2794)
			(end 0.12065 -0.3048)
			(stroke
				(width 0.1)
				(type default)
			)
			(layer "F.Fab")
		)
		(fp_line
			(start 0.12065 -0.3048)
			(end 0.67945 -0.3048)
			(stroke
				(width 0.1)
				(type default)
			)
			(layer "F.Fab")
		)
		(fp_line
			(start 0.120396 0.3048)
			(end 0.120396 0.2794)
			(stroke
				(width 0.1)
				(type default)
			)
			(layer "F.Fab")
		)
		(fp_line
			(start 0.120396 0.2794)
			(end -0.12065 0.2794)
			(stroke
				(width 0.1)
				(type default)
			)
			(layer "F.Fab")
		)
		(fp_line
			(start -0.12065 0.3048)
			(end -0.67945 0.3048)
			(stroke
				(width 0.1)
				(type default)
			)
			(layer "F.Fab")
		)
		(fp_line
			(start -0.12065 0.2794)
			(end -0.12065 0.3048)
			(stroke
				(width 0.1)
				(type default)
			)
			(layer "F.Fab")
		)
		(fp_line
			(start -0.12065 -0.2794)
			(end 0.12065 -0.2794)
			(stroke
				(width 0.1)
				(type default)
			)
			(layer "F.Fab")
		)
		(fp_line
			(start -0.12065 -0.305054)
			(end -0.12065 -0.2794)
			(stroke
				(width 0.1)
				(type default)
			)
			(layer "F.Fab")
		)
		(fp_line
			(start -0.67945 0.3048)
			(end -0.67945 -0.305054)
			(stroke
				(width 0.1)
				(type default)
			)
			(layer "F.Fab")
		)
		(fp_line
			(start -0.67945 -0.305054)
			(end -0.12065 -0.305054)
			(stroke
				(width 0.1)
				(type default)
			)
			(layer "F.Fab")
		)
		(pad "1" smd circle
			(at -0.40005 0 180)
			(size 0 0)
			(layers "F.Cu" "F.Mask" "F.Paste")
			(net "NC_P0V8_PEX2_ISEN6")
		)
		(pad "2" smd circle
			(at 0.40005 0 180)
			(size 0 0)
			(layers "F.Cu" "F.Mask" "F.Paste")
			(net "GND")
		)
	)
	(footprint ""
		(layer "F.Cu")
		(at 312.324496 -84.476336 180)
		(property "Reference" "U36"
			(at -2.890774 -0.503936 90)
			(unlocked yes)
			(layer "F.SilkS")
			(effects
				(font
					(size 0.7874 0.5842)
					(thickness 0.1524)
				)
				(justify left)
			)
		)
		(property "Value" ""
			(at 0 0 180)
			(layer "F.Fab")
			(effects
				(font
					(size 1.27 1.27)
				)
			)
		)
		(duplicate_pad_numbers_are_jumpers no)
		(fp_line
			(start 2.0574 1.651)
			(end -2.0574 1.651)
			(stroke
				(width 0.1524)
				(type default)
			)
			(layer "F.SilkS")
		)
		(fp_line
			(start 2.0574 -1.651)
			(end 2.0574 1.651)
			(stroke
				(width 0.1524)
				(type default)
			)
			(layer "F.SilkS")
		)
		(fp_line
			(start 0.381 -1.651)
			(end 2.0574 -1.651)
			(stroke
				(width 0.1524)
				(type default)
			)
			(layer "F.SilkS")
		)
		(fp_line
			(start 0 -1.016)
			(end 0.381 -1.651)
			(stroke
				(width 0.1524)
				(type default)
			)
			(layer "F.SilkS")
		)
		(fp_line
			(start -0.381 -1.651)
			(end 0 -1.016)
			(stroke
				(width 0.1524)
				(type default)
			)
			(layer "F.SilkS")
		)
		(fp_line
			(start -2.0574 1.651)
			(end -2.0574 -1.651)
			(stroke
				(width 0.1524)
				(type default)
			)
			(layer "F.SilkS")
		)
		(fp_line
			(start -2.0574 -1.651)
			(end -0.381 -1.651)
			(stroke
				(width 0.1524)
				(type default)
			)
			(layer "F.SilkS")
		)
		(fp_poly
			(pts
				(xy -2.71272 -0.719328) (xy -2.71272 -1.344168) (xy -2.159 -1.016)
			)
			(stroke
				(width 0)
				(type default)
			)
			(fill yes)
			(layer "F.SilkS")
		)
		(fp_line
			(start 1.599946 1.199896)
			(end 0.899922 1.199896)
			(stroke
				(width 0.1)
				(type default)
			)
			(layer "F.Fab")
		)
		(fp_line
			(start 1.599946 -1.199896)
			(end 1.599946 1.199896)
			(stroke
				(width 0.1)
				(type default)
			)
			(layer "F.Fab")
		)
		(fp_line
			(start 0.899922 1.549908)
			(end -0.899922 1.549908)
			(stroke
				(width 0.1)
				(type default)
			)
			(layer "F.Fab")
		)
		(fp_line
			(start 0.899922 1.199896)
			(end 0.899922 1.549908)
			(stroke
				(width 0.1)
				(type default)
			)
			(layer "F.Fab")
		)
		(fp_line
			(start 0.899922 -1.199896)
			(end 1.599946 -1.199896)
			(stroke
				(width 0.1)
				(type default)
			)
			(layer "F.Fab")
		)
		(fp_line
			(start 0.899922 -1.549908)
			(end 0.899922 -1.199896)
			(stroke
				(width 0.1)
				(type default)
			)
			(layer "F.Fab")
		)
		(fp_line
			(start -0.899922 1.549908)
			(end -0.899922 1.199896)
			(stroke
				(width 0.1)
				(type default)
			)
			(layer "F.Fab")
		)
		(fp_line
			(start -0.899922 1.199896)
			(end -1.599946 1.199896)
			(stroke
				(width 0.1)
				(type default)
			)
			(layer "F.Fab")
		)
		(fp_line
			(start -0.899922 -1.199896)
			(end -0.899922 -1.549908)
			(stroke
				(width 0.1)
				(type default)
			)
			(layer "F.Fab")
		)
		(fp_line
			(start -0.899922 -1.549908)
			(end 0.899922 -1.549908)
			(stroke
				(width 0.1)
				(type default)
			)
			(layer "F.Fab")
		)
		(fp_line
			(start -1.599946 1.199896)
			(end -1.599946 -1.199896)
			(stroke
				(width 0.1)
				(type default)
			)
			(layer "F.Fab")
		)
		(fp_line
			(start -1.599946 -1.199896)
			(end -0.899922 -1.199896)
			(stroke
				(width 0.1)
				(type default)
			)
			(layer "F.Fab")
		)
		(fp_poly
			(pts
				(xy -2.71272 -0.719328) (xy -2.71272 -1.344168) (xy -2.159 -1.016)
			)
			(stroke
				(width 0)
				(type default)
			)
			(fill yes)
			(layer "F.Fab")
		)
		(pad "1" smd rect
			(at -1.225042 -0.94996 90)
			(size 0.5588 1.3462)
			(layers "F.Cu" "F.Mask" "F.Paste")
			(net "HP_NIC5_PWRGD_R")
		)
		(pad "2" smd rect
			(at -1.225042 0 90)
			(size 0.5588 1.3462)
			(layers "F.Cu" "F.Mask" "F.Paste")
			(net "RST_NIC5_PERST_R_N")
		)
		(pad "3" smd rect
			(at -1.225042 0.94996 90)
			(size 0.5588 1.3462)
			(layers "F.Cu" "F.Mask" "F.Paste")
			(net "GND")
		)
		(pad "4" smd rect
			(at 1.225042 0.94996 90)
			(size 0.5588 1.3462)
			(layers "F.Cu" "F.Mask" "F.Paste")
			(net "RST_HP_NIC5_N")
		)
		(pad "5" smd rect
			(at 1.225042 -0.94996 90)
			(size 0.5588 1.3462)
			(layers "F.Cu" "F.Mask" "F.Paste")
			(net "P3V3_AUX")
		)
	)
	(footprint ""
		(layer "F.Cu")
		(at 131.797806 -122.780552)
		(property "Reference" "PC484"
			(at 0 0 0)
			(layer "F.SilkS")
			(hide yes)
			(effects
				(font
					(size 1.27 1.27)
				)
			)
		)
		(property "Value" ""
			(at 0 0 0)
			(layer "F.Fab")
			(effects
				(font
					(size 1.27 1.27)
				)
			)
		)
		(duplicate_pad_numbers_are_jumpers no)
		(fp_line
			(start -0.7874 -0.4064)
			(end 0.7874 -0.4064)
			(stroke
				(width 0.1524)
				(type default)
			)
			(layer "F.SilkS")
		)
		(fp_line
			(start -0.7874 0.4064)
			(end -0.7874 -0.4064)
			(stroke
				(width 0.1524)
				(type default)
			)
			(layer "F.SilkS")
		)
		(fp_line
			(start 0.7874 -0.4064)
			(end 0.7874 0.4064)
			(stroke
				(width 0.1524)
				(type default)
			)
			(layer "F.SilkS")
		)
		(fp_line
			(start 0.7874 0.4064)
			(end -0.7874 0.4064)
			(stroke
				(width 0.1524)
				(type default)
			)
			(layer "F.SilkS")
		)
		(fp_line
			(start -0.67945 -0.305054)
			(end -0.12065 -0.305054)
			(stroke
				(width 0.1)
				(type default)
			)
			(layer "F.Fab")
		)
		(fp_line
			(start -0.67945 0.3048)
			(end -0.67945 -0.305054)
			(stroke
				(width 0.1)
				(type default)
			)
			(layer "F.Fab")
		)
		(fp_line
			(start -0.12065 -0.305054)
			(end -0.12065 -0.2794)
			(stroke
				(width 0.1)
				(type default)
			)
			(layer "F.Fab")
		)
		(fp_line
			(start -0.12065 -0.2794)
			(end 0.12065 -0.2794)
			(stroke
				(width 0.1)
				(type default)
			)
			(layer "F.Fab")
		)
		(fp_line
			(start -0.12065 0.2794)
			(end -0.12065 0.3048)
			(stroke
				(width 0.1)
				(type default)
			)
			(layer "F.Fab")
		)
		(fp_line
			(start -0.12065 0.3048)
			(end -0.67945 0.3048)
			(stroke
				(width 0.1)
				(type default)
			)
			(layer "F.Fab")
		)
		(fp_line
			(start 0.120396 0.2794)
			(end -0.12065 0.2794)
			(stroke
				(width 0.1)
				(type default)
			)
			(layer "F.Fab")
		)
		(fp_line
			(start 0.120396 0.3048)
			(end 0.120396 0.2794)
			(stroke
				(width 0.1)
				(type default)
			)
			(layer "F.Fab")
		)
		(fp_line
			(start 0.12065 -0.3048)
			(end 0.67945 -0.3048)
			(stroke
				(width 0.1)
				(type default)
			)
			(layer "F.Fab")
		)
		(fp_line
			(start 0.12065 -0.2794)
			(end 0.12065 -0.3048)
			(stroke
				(width 0.1)
				(type default)
			)
			(layer "F.Fab")
		)
		(fp_line
			(start 0.67945 -0.3048)
			(end 0.67945 0.3048)
			(stroke
				(width 0.1)
				(type default)
			)
			(layer "F.Fab")
		)
		(fp_line
			(start 0.67945 0.3048)
			(end 0.120396 0.3048)
			(stroke
				(width 0.1)
				(type default)
			)
			(layer "F.Fab")
		)
		(pad "1" smd circle
			(at -0.40005 0)
			(size 0 0)
			(layers "F.Cu" "F.Mask" "F.Paste")
			(net "P3V3_AUX")
		)
		(pad "2" smd circle
			(at 0.40005 0)
			(size 0 0)
			(layers "F.Cu" "F.Mask" "F.Paste")
			(net "GND")
		)
	)
	(footprint ""
		(layer "F.Cu")
		(at 196.723508 -87.349076 -90)
		(property "Reference" "R199"
			(at 0 0 270)
			(layer "F.SilkS")
			(hide yes)
			(effects
				(font
					(size 1.27 1.27)
				)
			)
		)
		(property "Value" ""
			(at 0 0 270)
			(layer "F.Fab")
			(effects
				(font
					(size 1.27 1.27)
				)
			)
		)
		(duplicate_pad_numbers_are_jumpers no)
		(fp_line
			(start -0.7874 0.4064)
			(end -0.7874 -0.4064)
			(stroke
				(width 0.1524)
				(type default)
			)
			(layer "F.SilkS")
		)
		(fp_line
			(start 0.7874 0.4064)
			(end -0.7874 0.4064)
			(stroke
				(width 0.1524)
				(type default)
			)
			(layer "F.SilkS")
		)
		(fp_line
			(start -0.7874 -0.4064)
			(end 0.7874 -0.4064)
			(stroke
				(width 0.1524)
				(type default)
			)
			(layer "F.SilkS")
		)
		(fp_line
			(start 0.7874 -0.4064)
			(end 0.7874 0.4064)
			(stroke
				(width 0.1524)
				(type default)
			)
			(layer "F.SilkS")
		)
		(fp_line
			(start -0.67945 0.3048)
			(end -0.67945 -0.305054)
			(stroke
				(width 0.1)
				(type default)
			)
			(layer "F.Fab")
		)
		(fp_line
			(start -0.12065 0.3048)
			(end -0.67945 0.3048)
			(stroke
				(width 0.1)
				(type default)
			)
			(layer "F.Fab")
		)
		(fp_line
			(start 0.120396 0.3048)
			(end 0.120396 0.2794)
			(stroke
				(width 0.1)
				(type default)
			)
			(layer "F.Fab")
		)
		(fp_line
			(start 0.67945 0.3048)
			(end 0.120396 0.3048)
			(stroke
				(width 0.1)
				(type default)
			)
			(layer "F.Fab")
		)
		(fp_line
			(start -0.12065 0.2794)
			(end -0.12065 0.3048)
			(stroke
				(width 0.1)
				(type default)
			)
			(layer "F.Fab")
		)
		(fp_line
			(start 0.120396 0.2794)
			(end -0.12065 0.2794)
			(stroke
				(width 0.1)
				(type default)
			)
			(layer "F.Fab")
		)
		(fp_line
			(start -0.12065 -0.2794)
			(end 0.12065 -0.2794)
			(stroke
				(width 0.1)
				(type default)
			)
			(layer "F.Fab")
		)
		(fp_line
			(start 0.12065 -0.2794)
			(end 0.12065 -0.3048)
			(stroke
				(width 0.1)
				(type default)
			)
			(layer "F.Fab")
		)
		(fp_line
			(start 0.12065 -0.3048)
			(end 0.67945 -0.3048)
			(stroke
				(width 0.1)
				(type default)
			)
			(layer "F.Fab")
		)
		(fp_line
			(start 0.67945 -0.3048)
			(end 0.67945 0.3048)
			(stroke
				(width 0.1)
				(type default)
			)
			(layer "F.Fab")
		)
		(fp_line
			(start -0.67945 -0.305054)
			(end -0.12065 -0.305054)
			(stroke
				(width 0.1)
				(type default)
			)
			(layer "F.Fab")
		)
		(fp_line
			(start -0.12065 -0.305054)
			(end -0.12065 -0.2794)
			(stroke
				(width 0.1)
				(type default)
			)
			(layer "F.Fab")
		)
		(pad "1" smd circle
			(at -0.40005 0 270)
			(size 0 0)
			(layers "F.Cu" "F.Mask" "F.Paste")
			(net "RST_NIC3_PERST1_R_N")
		)
		(pad "2" smd circle
			(at 0.40005 0 270)
			(size 0 0)
			(layers "F.Cu" "F.Mask" "F.Paste")
			(net "RST_HP_NIC3_BUF_N")
		)
	)
	(footprint ""
		(layer "F.Cu")
		(at 78.45933 -22.955504 90)
		(property "Reference" "R1657"
			(at 0 0 90)
			(layer "F.SilkS")
			(hide yes)
			(effects
				(font
					(size 1.27 1.27)
				)
			)
		)
		(property "Value" ""
			(at 0 0 90)
			(layer "F.Fab")
			(effects
				(font
					(size 1.27 1.27)
				)
			)
		)
		(duplicate_pad_numbers_are_jumpers no)
		(fp_line
			(start 0.7874 -0.4064)
			(end 0.7874 0.4064)
			(stroke
				(width 0.1524)
				(type default)
			)
			(layer "F.SilkS")
		)
		(fp_line
			(start -0.7874 -0.4064)
			(end 0.7874 -0.4064)
			(stroke
				(width 0.1524)
				(type default)
			)
			(layer "F.SilkS")
		)
		(fp_line
			(start 0.7874 0.4064)
			(end -0.7874 0.4064)
			(stroke
				(width 0.1524)
				(type default)
			)
			(layer "F.SilkS")
		)
		(fp_line
			(start -0.7874 0.4064)
			(end -0.7874 -0.4064)
			(stroke
				(width 0.1524)
				(type default)
			)
			(layer "F.SilkS")
		)
		(fp_line
			(start -0.12065 -0.305054)
			(end -0.12065 -0.2794)
			(stroke
				(width 0.1)
				(type default)
			)
			(layer "F.Fab")
		)
		(fp_line
			(start -0.67945 -0.305054)
			(end -0.12065 -0.305054)
			(stroke
				(width 0.1)
				(type default)
			)
			(layer "F.Fab")
		)
		(fp_line
			(start 0.67945 -0.3048)
			(end 0.67945 0.3048)
			(stroke
				(width 0.1)
				(type default)
			)
			(layer "F.Fab")
		)
		(fp_line
			(start 0.12065 -0.3048)
			(end 0.67945 -0.3048)
			(stroke
				(width 0.1)
				(type default)
			)
			(layer "F.Fab")
		)
		(fp_line
			(start 0.12065 -0.2794)
			(end 0.12065 -0.3048)
			(stroke
				(width 0.1)
				(type default)
			)
			(layer "F.Fab")
		)
		(fp_line
			(start -0.12065 -0.2794)
			(end 0.12065 -0.2794)
			(stroke
				(width 0.1)
				(type default)
			)
			(layer "F.Fab")
		)
		(fp_line
			(start 0.120396 0.2794)
			(end -0.12065 0.2794)
			(stroke
				(width 0.1)
				(type default)
			)
			(layer "F.Fab")
		)
		(fp_line
			(start -0.12065 0.2794)
			(end -0.12065 0.3048)
			(stroke
				(width 0.1)
				(type default)
			)
			(layer "F.Fab")
		)
		(fp_line
			(start 0.67945 0.3048)
			(end 0.120396 0.3048)
			(stroke
				(width 0.1)
				(type default)
			)
			(layer "F.Fab")
		)
		(fp_line
			(start 0.120396 0.3048)
			(end 0.120396 0.2794)
			(stroke
				(width 0.1)
				(type default)
			)
			(layer "F.Fab")
		)
		(fp_line
			(start -0.12065 0.3048)
			(end -0.67945 0.3048)
			(stroke
				(width 0.1)
				(type default)
			)
			(layer "F.Fab")
		)
		(fp_line
			(start -0.67945 0.3048)
			(end -0.67945 -0.305054)
			(stroke
				(width 0.1)
				(type default)
			)
			(layer "F.Fab")
		)
		(pad "1" smd circle
			(at -0.40005 0 90)
			(size 0 0)
			(layers "F.Cu" "F.Mask" "F.Paste")
			(net "SMB_BIC_I2C9_MUX0_SSD2_R_SCL")
		)
		(pad "2" smd circle
			(at 0.40005 0 90)
			(size 0 0)
			(layers "F.Cu" "F.Mask" "F.Paste")
			(net "SMB_ISO_SSD2_SCL")
		)
	)
	(footprint ""
		(layer "F.Cu")
		(at 180.814472 -343.952322 90)
		(property "Reference" "C385"
			(at 0 0 90)
			(layer "F.SilkS")
			(hide yes)
			(effects
				(font
					(size 1.27 1.27)
				)
			)
		)
		(property "Value" ""
			(at 0 0 90)
			(layer "F.Fab")
			(effects
				(font
					(size 1.27 1.27)
				)
			)
		)
		(duplicate_pad_numbers_are_jumpers no)
		(fp_line
			(start 0.299974 -0.150114)
			(end 0.299974 0.150114)
			(stroke
				(width 0.1)
				(type default)
			)
			(layer "F.Fab")
		)
		(fp_line
			(start -0.299974 -0.150114)
			(end 0.299974 -0.150114)
			(stroke
				(width 0.1)
				(type default)
			)
			(layer "F.Fab")
		)
		(fp_line
			(start 0.299974 0.150114)
			(end -0.299974 0.150114)
			(stroke
				(width 0.1)
				(type default)
			)
			(layer "F.Fab")
		)
		(fp_line
			(start -0.299974 0.150114)
			(end -0.299974 -0.150114)
			(stroke
				(width 0.1)
				(type default)
			)
			(layer "F.Fab")
		)
		(pad "1" smd rect
			(at -0.2667 0 90)
			(size 0.3048 0.381)
			(layers "F.Cu" "F.Mask" "F.Paste")
			(net "P5E_PEX1_STN7_TX_DN<121>")
		)
		(pad "2" smd rect
			(at 0.2667 0 90)
			(size 0.3048 0.381)
			(layers "F.Cu" "F.Mask" "F.Paste")
			(net "P5E_PEX1_STN7_TX_C_DN<121>")
		)
	)
)
